# BASEBOARD_FAB2 (Tioga Pass) — schematic netlist excerpt (pin names and nets, part order shuffled) for the footprints in the layout excerpt that follows; sources: Cadence DE-HDL packaged netlist, KiCad conversion of Wiwynn_Tioga_Pass_MB.brd

U1E2  TTL1G08  NC7SZ08 IC  pkg SOTLF  page 161
  A(0)  = FM_CTNR_PS_ON
  B(0)  = FM_DISABLE_FAN_N
  Y(0)  = FM_ENABLE_FAN_POWER

CF19  SC22P50V2JN-4GP  5%  pkg SMD-BCG  page 223 : \1\ = VR_PVDDQ_GHJ_AIREF1 ; \2\ = ISENSE_PVDDQ_GHJ_PH1_IMON
R6D9  RES  150.0 1% CHIP  pkg 0402  page 92 : A = PVCCIO_CPU0 ; B = H_CPU0_MSMI_G_N

(kicad_pcb
	(version 20260206)
	(generator "pcbnew")
	(generator_version "10.0")
	(general
		(thickness 1.6)
		(legacy_teardrops no)
	)
	(paper "A4")
	(title_block
		(title "Wiwynn_Tioga_Pass_MB.brd")
		(comment 1 "Tioga Pass / footprints 2279-2281 of 4770")
	)
	(layers
		(0 "F.Cu" signal "TOP")
		(4 "In1.Cu" signal "L2GND")
		(6 "In2.Cu" signal "L3")
		(8 "In3.Cu" signal "L4GND")
		(10 "In4.Cu" signal "L5")
		(12 "In5.Cu" signal "L6GND")
		(14 "In6.Cu" signal "L7VCC")
		(16 "In7.Cu" signal "L8VCC")
		(18 "In8.Cu" signal "L9GND")
		(20 "In9.Cu" signal "L10")
		(22 "In10.Cu" signal "L11GND")
		(24 "In11.Cu" signal "L12")
		(26 "In12.Cu" signal "L13GND")
		(2 "B.Cu" signal "BOTTOM")
		(9 "F.Adhes" user "F.Adhesive")
		(11 "B.Adhes" user "B.Adhesive")
		(13 "F.Paste" user "Package Geometry/Pastemask Top")
		(15 "B.Paste" user "Package Geometry/Pastemask Bottom")
		(5 "F.SilkS" user "Ref Des/Silkscreen Top")
		(7 "B.SilkS" user "Ref Des/Silkscreen Bottom")
		(1 "F.Mask" user "Board Geometry/Soldermask Top")
		(3 "B.Mask" user "Board Geometry/Soldermask Bottom")
		(17 "Dwgs.User" user "User.Drawings")
		(19 "Cmts.User" user "User.Comments")
		(21 "Eco1.User" user "User.Eco1")
		(23 "Eco2.User" user "User.Eco2")
		(25 "Edge.Cuts" user "Board Geometry/Outline")
		(27 "Margin" user)
		(31 "F.CrtYd" user "Package Geometry/Place Bound Top")
		(29 "B.CrtYd" user "Package Geometry/Place Bound Bottom")
		(35 "F.Fab" user "Ref Des/Assembly Top")
		(33 "B.Fab" user "Ref Des/Assembly Bottom")
	)
	(footprint ""
		(layer "F.Cu")
		(at 5.923788 -3.00101 -90)
		(property "Reference" "CF19"
			(at 0 0 270)
			(layer "F.SilkS")
			(hide yes)
			(effects
				(font
					(size 1.27 1.27)
				)
			)
		)
		(property "Value" "*"
			(at 1.1811 -2.8194 270)
			(unlocked yes)
			(layer "F.Fab")
			(hide yes)
			(effects
				(font
					(size 1.27 1.016)
					(thickness 0.1524)
				)
			)
		)
		(property "Device Type" "SC22P50V2JN-4GP_SMD-BCG-SC22P5A"
			(at 1.1811 -4.3434 270)
			(unlocked yes)
			(layer "F.Fab")
			(hide yes)
			(effects
				(font
					(size 1.27 1.016)
					(thickness 0.1524)
				)
			)
		)
		(duplicate_pad_numbers_are_jumpers no)
		(fp_rect
			(start -0.4318 0.9525)
			(end 0.4318 -0.9525)
			(stroke
				(width 0)
				(type default)
			)
			(fill no)
			(layer "F.CrtYd")
		)
		(fp_rect
			(start -0.4318 0.9525)
			(end 0.4318 -0.9525)
			(stroke
				(width 0)
				(type default)
			)
			(fill no)
			(layer "F.Fab")
		)
		(pad "1" smd custom
			(at 0 -0.4445 270)
			(size 0.1524 0.1524)
			(layers "F.Cu" "F.Mask" "F.Paste")
			(net "VR_PVDDQ_GHJ_AIREF1")
			(options
				(clearance outline)
				(anchor circle)
			)
			(primitives
				(gr_poly
					(pts
						(arc
							(start 0.3048 -0.2032)
							(mid 0.275042 -0.275042)
							(end 0.2032 -0.3048)
						)
						(arc
							(start -0.2032 -0.3048)
							(mid -0.275042 -0.275042)
							(end -0.3048 -0.2032)
						)
						(arc
							(start -0.3048 0.2032)
							(mid -0.275042 0.275042)
							(end -0.2032 0.3048)
						)
						(arc
							(start 0.2032 0.3048)
							(mid 0.275042 0.275042)
							(end 0.3048 0.2032)
						)
					)
					(width 0)
					(fill yes)
				)
			)
		)
		(pad "2" smd custom
			(at 0 0.4445 270)
			(size 0.1524 0.1524)
			(layers "F.Cu" "F.Mask" "F.Paste")
			(net "ISENSE_PVDDQ_GHJ_PH1_IMON")
			(options
				(clearance outline)
				(anchor circle)
			)
			(primitives
				(gr_poly
					(pts
						(arc
							(start 0.3048 -0.2032)
							(mid 0.275042 -0.275042)
							(end 0.2032 -0.3048)
						)
						(arc
							(start -0.2032 -0.3048)
							(mid -0.275042 -0.275042)
							(end -0.3048 -0.2032)
						)
						(arc
							(start -0.3048 0.2032)
							(mid -0.275042 0.275042)
							(end -0.2032 0.3048)
						)
						(arc
							(start 0.2032 0.3048)
							(mid 0.275042 0.275042)
							(end 0.3048 0.2032)
						)
					)
					(width 0)
					(fill yes)
				)
			)
		)
	)
	(footprint ""
		(layer "F.Cu")
		(at 20.2946 -41.402 180)
		(property "Reference" "U1E2"
			(at 2.2606 2.25933 0)
			(unlocked yes)
			(layer "F.SilkS")
			(effects
				(font
					(size 0.7874 0.5842)
					(thickness 0.1524)
				)
				(justify left)
			)
		)
		(property "Value" ""
			(at 0 0 180)
			(layer "F.Fab")
			(effects
				(font
					(size 1.27 1.27)
				)
			)
		)
		(duplicate_pad_numbers_are_jumpers no)
		(fp_circle
			(center -1.2192 -0.35814)
			(end -1.3462 -0.35814)
			(stroke
				(width 0.254)
				(type default)
			)
			(fill no)
			(layer "F.SilkS")
		)
		(fp_poly
			(pts
				(xy 0.21463 -0.450088) (xy 1.56337 -0.450088) (xy 1.56337 1.75006) (xy 0.21463 1.75006)
			)
			(stroke
				(width 0)
				(type default)
			)
			(fill no)
			(layer "F.CrtYd")
		)
		(fp_line
			(start 1.56337 1.75006)
			(end 0.21463 1.75006)
			(stroke
				(width 0.1)
				(type default)
			)
			(layer "F.Fab")
		)
		(fp_line
			(start 1.56337 -0.450088)
			(end 1.56337 1.75006)
			(stroke
				(width 0.1)
				(type default)
			)
			(layer "F.Fab")
		)
		(fp_line
			(start 0.21463 1.75006)
			(end 0.21463 -0.450088)
			(stroke
				(width 0.1)
				(type default)
			)
			(layer "F.Fab")
		)
		(fp_line
			(start 0.21463 -0.450088)
			(end 1.56337 -0.450088)
			(stroke
				(width 0.1)
				(type default)
			)
			(layer "F.Fab")
		)
		(fp_circle
			(center -0.4699 -0.8382)
			(end -0.5969 -0.8382)
			(stroke
				(width 0.254)
				(type default)
			)
			(fill no)
			(layer "F.Fab")
		)
		(pad "1" smd rect
			(at 0 0 180)
			(size 1.016 0.381)
			(layers "F.Cu" "F.Mask" "F.Paste")
			(net "FM_CTNR_PS_ON")
		)
		(pad "2" smd rect
			(at 0 0.649986 180)
			(size 1.016 0.381)
			(layers "F.Cu" "F.Mask" "F.Paste")
			(net "FM_DISABLE_FAN_N")
		)
		(pad "3" smd rect
			(at 0 1.299972 180)
			(size 1.016 0.381)
			(layers "F.Cu" "F.Mask" "F.Paste")
			(net "GND")
		)
		(pad "4" smd rect
			(at 1.778 1.299972 180)
			(size 1.016 0.381)
			(layers "F.Cu" "F.Mask" "F.Paste")
			(net "FM_ENABLE_FAN_POWER")
		)
		(pad "5" smd rect
			(at 1.778 0 180)
			(size 1.016 0.381)
			(layers "F.Cu" "F.Mask" "F.Paste")
			(net "P3V3_STBY")
		)
	)
	(footprint ""
		(layer "F.Cu")
		(at 281.178 -73.152 90)
		(property "Reference" "R6D9"
			(at 0 0 90)
			(layer "F.SilkS")
			(hide yes)
			(effects
				(font
					(size 1.27 1.27)
				)
			)
		)
		(property "Value" ""
			(at 0 0 90)
			(layer "F.Fab")
			(effects
				(font
					(size 1.27 1.27)
				)
			)
		)
		(duplicate_pad_numbers_are_jumpers no)
		(fp_rect
			(start -0.2794 -0.1016)
			(end 0.2794 0.9906)
			(stroke
				(width 0)
				(type default)
			)
			(fill no)
			(layer "F.CrtYd")
		)
		(fp_line
			(start 0.2794 -0.1016)
			(end -0.2794 -0.1016)
			(stroke
				(width 0.1)
				(type default)
			)
			(layer "F.Fab")
		)
		(fp_line
			(start -0.2794 -0.1016)
			(end -0.2794 0.9906)
			(stroke
				(width 0.1)
				(type default)
			)
			(layer "F.Fab")
		)
		(fp_line
			(start 0.2794 0.9906)
			(end 0.2794 -0.1016)
			(stroke
				(width 0.1)
				(type default)
			)
			(layer "F.Fab")
		)
		(fp_line
			(start -0.2794 0.9906)
			(end 0.2794 0.9906)
			(stroke
				(width 0.1)
				(type default)
			)
			(layer "F.Fab")
		)
		(pad "1" smd rect
			(at 0 0 90)
			(size 0.508 0.508)
			(layers "F.Cu" "F.Mask" "F.Paste")
			(net "PVCCIO_CPU0")
		)
		(pad "2" smd rect
			(at 0 0.889 90)
			(size 0.508 0.508)
			(layers "F.Cu" "F.Mask" "F.Paste")
			(net "H_CPU0_MSMI_G_N")
		)
		(zone
			(layer "F.Cu")
			(hatch none 0.5)
			(connect_pads
				(clearance 0)
			)
			(min_thickness 0.25)
			(keepout
				(tracks allowed)
				(vias not_allowed)
				(pads allowed)
				(copperpour not_allowed)
				(footprints allowed)
			)
			(placement
				(enabled no)
				(sheetname "")
			)
			(fill
				(thermal_gap 0.5)
				(thermal_bridge_width 0.5)
				(island_removal_mode 0)
			)
			(polygon
				(pts
					(xy 281.432 -72.898) (xy 281.813 -72.898) (xy 281.813 -73.406) (xy 281.432 -73.406)
				)
			)
		)
		(zone
			(layer "F.Cu")
			(hatch none 0.5)
			(connect_pads
				(clearance 0)
			)
			(min_thickness 0.25)
			(keepout
				(tracks not_allowed)
				(vias allowed)
				(pads allowed)
				(copperpour not_allowed)
				(footprints allowed)
			)
			(placement
				(enabled no)
				(sheetname "")
			)
			(fill
				(thermal_gap 0.5)
				(thermal_bridge_width 0.5)
				(island_removal_mode 0)
			)
			(polygon
				(pts
					(xy 281.432 -72.898) (xy 281.813 -72.898) (xy 281.813 -73.406) (xy 281.432 -73.406)
				)
			)
		)
	)
)
